(kicad_pcb
	(version 20260206)
	(generator "pcbnew")
	(generator_version "10.0")
	(general
		(thickness 1.6)
		(legacy_teardrops no)
	)
	(paper "A4")
	(title_block
		(title "Bryce Canyon_IOM_IOC_16318-2_OCP.brd")
		(comment 1 "Bryce Canyon / footprints 1107-1115 of 1605")
	)
	(layers
		(0 "F.Cu" signal "TOP")
		(4 "In1.Cu" signal "L2GND")
		(6 "In2.Cu" signal "L3")
		(8 "In3.Cu" signal "L4VCC")
		(10 "In4.Cu" signal "L5VCC")
		(12 "In5.Cu" signal "L6")
		(14 "In6.Cu" signal "L7GND")
		(2 "B.Cu" signal "BOTTOM")
		(9 "F.Adhes" user "F.Adhesive")
		(11 "B.Adhes" user "B.Adhesive")
		(13 "F.Paste" user "Package Geometry/Pastemask Top")
		(15 "B.Paste" user "Package Geometry/Pastemask Bottom")
		(5 "F.SilkS" user "Ref Des/Silkscreen Top")
		(7 "B.SilkS" user "Ref Des/Silkscreen Bottom")
		(1 "F.Mask" user "Board Geometry/Soldermask Top")
		(3 "B.Mask" user "Board Geometry/Soldermask Bottom")
		(17 "Dwgs.User" user "User.Drawings")
		(19 "Cmts.User" user "User.Comments")
		(21 "Eco1.User" user "User.Eco1")
		(23 "Eco2.User" user "User.Eco2")
		(25 "Edge.Cuts" user "Board Geometry/Outline")
		(27 "Margin" user)
		(31 "F.CrtYd" user "Package Geometry/Place Bound Top")
		(29 "B.CrtYd" user "Package Geometry/Place Bound Bottom")
		(35 "F.Fab" user "Ref Des/Assembly Top")
		(33 "B.Fab" user "Ref Des/Assembly Bottom")
	)
	(footprint ""
		(layer "B.Cu")
		(at 39.37 -126.5174)
		(property "Reference" "R314"
			(at 0 0 0)
			(layer "B.SilkS")
			(hide yes)
			(effects
				(font
					(size 1.27 1.27)
				)
				(justify mirror)
			)
		)
		(property "Value" "0R2J-2-GP"
			(at -0.064008 -3.993896 0)
			(unlocked yes)
			(layer "B.Fab")
			(hide yes)
			(effects
				(font
					(size 1.016 1.016)
					(thickness 0.1524)
				)
				(justify mirror)
			)
		)
		(property "Device Type" "R402H16"
			(at -0.064008 -5.517896 0)
			(unlocked yes)
			(layer "B.Fab")
			(hide yes)
			(effects
				(font
					(size 1.016 1.016)
					(thickness 0.1524)
				)
				(justify mirror)
			)
		)
		(duplicate_pad_numbers_are_jumpers no)
		(fp_line
			(start -0.508 -0.9398)
			(end 0.508 -0.9398)
			(stroke
				(width 0.1524)
				(type default)
			)
			(layer "B.SilkS")
		)
		(fp_line
			(start 0.508 -0.9398)
			(end 0.508 0.9398)
			(stroke
				(width 0.1524)
				(type default)
			)
			(layer "B.SilkS")
		)
		(fp_rect
			(start 0.508 0.9398)
			(end -0.508 -0.9398)
			(stroke
				(width 0)
				(type default)
			)
			(fill no)
			(layer "B.CrtYd")
		)
		(fp_rect
			(start 0.508 0.9398)
			(end -0.508 -0.9398)
			(stroke
				(width 0)
				(type default)
			)
			(fill no)
			(layer "B.Fab")
		)
		(pad "1" smd custom
			(at 0 -0.4445 180)
			(size 0.1397 0.1397)
			(layers "B.Cu" "B.Mask" "B.Paste")
			(net "BMC_EXTRST_N")
			(options
				(clearance outline)
				(anchor circle)
			)
			(primitives
				(gr_poly
					(pts
						(arc
							(start -0.1778 0.2794)
							(mid -0.249642 0.249642)
							(end -0.2794 0.1778)
						)
						(arc
							(start -0.2794 -0.1778)
							(mid -0.249642 -0.249642)
							(end -0.1778 -0.2794)
						)
						(arc
							(start 0.1778 -0.2794)
							(mid 0.249642 -0.249642)
							(end 0.2794 -0.1778)
						)
						(arc
							(start 0.2794 0.1778)
							(mid 0.249642 0.249642)
							(end 0.1778 0.2794)
						)
					)
					(width 0)
					(fill yes)
				)
			)
		)
		(pad "2" smd custom
			(at 0 0.4445 180)
			(size 0.1397 0.1397)
			(layers "B.Cu" "B.Mask" "B.Paste")
			(net "RST_BMC_EXTRST_N")
			(options
				(clearance outline)
				(anchor circle)
			)
			(primitives
				(gr_poly
					(pts
						(arc
							(start -0.1778 0.2794)
							(mid -0.249642 0.249642)
							(end -0.2794 0.1778)
						)
						(arc
							(start -0.2794 -0.1778)
							(mid -0.249642 -0.249642)
							(end -0.1778 -0.2794)
						)
						(arc
							(start 0.1778 -0.2794)
							(mid 0.249642 -0.249642)
							(end 0.2794 -0.1778)
						)
						(arc
							(start 0.2794 0.1778)
							(mid 0.249642 0.249642)
							(end 0.1778 0.2794)
						)
					)
					(width 0)
					(fill yes)
				)
			)
		)
	)
	(footprint ""
		(layer "B.Cu")
		(at 87.691976 -148.73224 180)
		(property "Reference" "R429"
			(at 0 0 0)
			(layer "B.SilkS")
			(hide yes)
			(effects
				(font
					(size 1.27 1.27)
				)
				(justify mirror)
			)
		)
		(property "Value" "4K7R2F-GP"
			(at -0.064008 -3.993896 180)
			(unlocked yes)
			(layer "B.Fab")
			(hide yes)
			(effects
				(font
					(size 1.016 1.016)
					(thickness 0.1524)
				)
				(justify mirror)
			)
		)
		(property "Device Type" "R402H16"
			(at -0.064008 -5.517896 180)
			(unlocked yes)
			(layer "B.Fab")
			(hide yes)
			(effects
				(font
					(size 1.016 1.016)
					(thickness 0.1524)
				)
				(justify mirror)
			)
		)
		(duplicate_pad_numbers_are_jumpers no)
		(fp_line
			(start 0.508 -0.9398)
			(end 0.508 0.9398)
			(stroke
				(width 0.1524)
				(type default)
			)
			(layer "B.SilkS")
		)
		(fp_line
			(start -0.508 -0.9398)
			(end 0.508 -0.9398)
			(stroke
				(width 0.1524)
				(type default)
			)
			(layer "B.SilkS")
		)
		(fp_rect
			(start 0.508 0.9398)
			(end -0.508 -0.9398)
			(stroke
				(width 0)
				(type default)
			)
			(fill no)
			(layer "B.CrtYd")
		)
		(fp_rect
			(start 0.508 0.9398)
			(end -0.508 -0.9398)
			(stroke
				(width 0)
				(type default)
			)
			(fill no)
			(layer "B.Fab")
		)
		(pad "1" smd custom
			(at 0 -0.4445)
			(size 0.1397 0.1397)
			(layers "B.Cu" "B.Mask" "B.Paste")
			(net "TCA9555_A1")
			(options
				(clearance outline)
				(anchor circle)
			)
			(primitives
				(gr_poly
					(pts
						(arc
							(start -0.1778 0.2794)
							(mid -0.249642 0.249642)
							(end -0.2794 0.1778)
						)
						(arc
							(start -0.2794 -0.1778)
							(mid -0.249642 -0.249642)
							(end -0.1778 -0.2794)
						)
						(arc
							(start 0.1778 -0.2794)
							(mid 0.249642 -0.249642)
							(end 0.2794 -0.1778)
						)
						(arc
							(start 0.2794 0.1778)
							(mid 0.249642 0.249642)
							(end 0.1778 0.2794)
						)
					)
					(width 0)
					(fill yes)
				)
			)
		)
		(pad "2" smd custom
			(at 0 0.4445)
			(size 0.1397 0.1397)
			(layers "B.Cu" "B.Mask" "B.Paste")
			(net "GND")
			(options
				(clearance outline)
				(anchor circle)
			)
			(primitives
				(gr_poly
					(pts
						(arc
							(start -0.1778 0.2794)
							(mid -0.249642 0.249642)
							(end -0.2794 0.1778)
						)
						(arc
							(start -0.2794 -0.1778)
							(mid -0.249642 -0.249642)
							(end -0.1778 -0.2794)
						)
						(arc
							(start 0.1778 -0.2794)
							(mid 0.249642 -0.249642)
							(end 0.2794 -0.1778)
						)
						(arc
							(start 0.2794 0.1778)
							(mid 0.249642 0.249642)
							(end 0.1778 0.2794)
						)
					)
					(width 0)
					(fill yes)
				)
			)
		)
	)
	(footprint ""
		(layer "B.Cu")
		(at 201.177398 -49.788572 -90)
		(property "Reference" "C335"
			(at 0 0 90)
			(layer "B.SilkS")
			(hide yes)
			(effects
				(font
					(size 1.27 1.27)
				)
				(justify mirror)
			)
		)
		(property "Value" "SC10U6D3V5KX-4GP"
			(at 0.0762 -6.1214 270)
			(unlocked yes)
			(layer "B.Fab")
			(hide yes)
			(effects
				(font
					(size 1.016 1.016)
					(thickness 0.1524)
				)
				(justify mirror)
			)
		)
		(property "Device Type" "C805H58"
			(at 0.0762 -8.1534 270)
			(unlocked yes)
			(layer "B.Fab")
			(hide yes)
			(effects
				(font
					(size 1.016 1.016)
					(thickness 0.1524)
				)
				(justify mirror)
			)
		)
		(duplicate_pad_numbers_are_jumpers no)
		(fp_line
			(start -0.635 0)
			(end 0.635 0)
			(stroke
				(width 0.508)
				(type default)
			)
			(layer "B.SilkS")
		)
		(fp_rect
			(start 0.9652 1.778)
			(end -0.9652 -1.778)
			(stroke
				(width 0)
				(type default)
			)
			(fill no)
			(layer "B.CrtYd")
		)
		(fp_poly
			(pts
				(xy 0.9652 -1.778) (xy -0.9652 -1.778) (xy -0.9652 1.778) (xy 0.9652 1.778)
			)
			(stroke
				(width 0)
				(type default)
			)
			(fill no)
			(layer "B.Fab")
		)
		(pad "1" smd rect
			(at 0 -0.9652 90)
			(size 1.397 1.143)
			(layers "B.Cu" "B.Mask" "B.Paste")
			(net "SYS_PLL_VDD")
		)
		(pad "2" smd rect
			(at 0 0.9652 90)
			(size 1.397 1.143)
			(layers "B.Cu" "B.Mask" "B.Paste")
			(net "GND")
		)
	)
	(footprint ""
		(layer "B.Cu")
		(at 177.9778 -77.4954)
		(property "Reference" "TP103"
			(at 0 0 0)
			(layer "B.SilkS")
			(hide yes)
			(effects
				(font
					(size 1.27 1.27)
				)
				(justify mirror)
			)
		)
		(property "Value" "TPAD28-2-GP"
			(at 0.0127 -1.6637 0)
			(unlocked yes)
			(layer "B.Fab")
			(hide yes)
			(effects
				(font
					(size 1.016 1.016)
					(thickness 0.1524)
				)
				(justify mirror)
			)
		)
		(property "Device Type" "TPAD28"
			(at 0.0127 -3.1877 0)
			(unlocked yes)
			(layer "B.Fab")
			(hide yes)
			(effects
				(font
					(size 1.016 1.016)
					(thickness 0.1524)
				)
				(justify mirror)
			)
		)
		(duplicate_pad_numbers_are_jumpers no)
		(fp_poly
			(pts
				(arc
					(start 0.3556 0)
					(mid -0.3556 0)
					(end 0.3556 0)
				)
			)
			(stroke
				(width 0)
				(type default)
			)
			(fill no)
			(layer "B.CrtYd")
		)
		(fp_poly
			(pts
				(arc
					(start 0.6096 0)
					(mid -0.6096 0)
					(end 0.6096 0)
				)
			)
			(stroke
				(width 0)
				(type default)
			)
			(fill no)
			(layer "B.Fab")
		)
		(pad "1" smd circle
			(at 0 0 180)
			(size 0.7112 0.7112)
			(layers "B.Cu" "B.Mask" "B.Paste")
			(net "IOC_GPIO_18")
		)
	)
	(footprint ""
		(layer "B.Cu")
		(at 93.246702 -158.624778)
		(property "Reference" "C11"
			(at 0 0 0)
			(layer "B.SilkS")
			(hide yes)
			(effects
				(font
					(size 1.27 1.27)
				)
				(justify mirror)
			)
		)
		(property "Value" "SC1U16V2KX-7-GP"
			(at -1.7526 -1.6002 0)
			(unlocked yes)
			(layer "B.Fab")
			(hide yes)
			(effects
				(font
					(size 1.016 1.016)
					(thickness 0.1524)
				)
				(justify mirror)
			)
		)
		(property "Device Type" "C402-TO0D2H24"
			(at -1.7526 -3.1242 0)
			(unlocked yes)
			(layer "B.Fab")
			(hide yes)
			(effects
				(font
					(size 1.016 1.016)
					(thickness 0.1524)
				)
				(justify mirror)
			)
		)
		(duplicate_pad_numbers_are_jumpers no)
		(fp_rect
			(start 0.4826 0.889)
			(end -0.4826 -0.889)
			(stroke
				(width 0)
				(type default)
			)
			(fill no)
			(layer "B.CrtYd")
		)
		(fp_rect
			(start 0.4826 0.889)
			(end -0.4826 -0.889)
			(stroke
				(width 0)
				(type default)
			)
			(fill no)
			(layer "B.Fab")
		)
		(pad "1" smd custom
			(at 0 -0.4572 180)
			(size 0.1524 0.1524)
			(layers "B.Cu" "B.Mask" "B.Paste")
			(net "P3V3_STBY")
			(options
				(clearance outline)
				(anchor circle)
			)
			(primitives
				(gr_poly
					(pts
						(arc
							(start -0.254 -0.3048)
							(mid -0.325842 -0.275042)
							(end -0.3556 -0.2032)
						)
						(arc
							(start -0.3556 0.2032)
							(mid -0.325842 0.275042)
							(end -0.254 0.3048)
						)
						(arc
							(start 0.254 0.3048)
							(mid 0.325842 0.275042)
							(end 0.3556 0.2032)
						)
						(arc
							(start 0.3556 -0.2032)
							(mid 0.325842 -0.275042)
							(end 0.254 -0.3048)
						)
					)
					(width 0)
					(fill yes)
				)
			)
		)
		(pad "2" smd custom
			(at 0 0.4572 180)
			(size 0.1524 0.1524)
			(layers "B.Cu" "B.Mask" "B.Paste")
			(net "GND")
			(options
				(clearance outline)
				(anchor circle)
			)
			(primitives
				(gr_poly
					(pts
						(arc
							(start -0.254 -0.3048)
							(mid -0.325842 -0.275042)
							(end -0.3556 -0.2032)
						)
						(arc
							(start -0.3556 0.2032)
							(mid -0.325842 0.275042)
							(end -0.254 0.3048)
						)
						(arc
							(start 0.254 0.3048)
							(mid 0.325842 0.275042)
							(end 0.3556 0.2032)
						)
						(arc
							(start 0.3556 -0.2032)
							(mid 0.325842 -0.275042)
							(end 0.254 -0.3048)
						)
					)
					(width 0)
					(fill yes)
				)
			)
		)
	)
	(footprint ""
		(layer "B.Cu")
		(at 200.75144 -61.2648 180)
		(property "Reference" "C439"
			(at 0 0 0)
			(layer "B.SilkS")
			(hide yes)
			(effects
				(font
					(size 1.27 1.27)
				)
				(justify mirror)
			)
		)
		(property "Value" "SCD1U16V2KX-3GP"
			(at -1.1811 -2.7051 180)
			(unlocked yes)
			(layer "B.Fab")
			(hide yes)
			(effects
				(font
					(size 1.016 1.016)
					(thickness 0.1524)
				)
				(justify mirror)
			)
		)
		(property "Device Type" "C402H22"
			(at -1.1811 -4.2291 180)
			(unlocked yes)
			(layer "B.Fab")
			(hide yes)
			(effects
				(font
					(size 1.016 1.016)
					(thickness 0.1524)
				)
				(justify mirror)
			)
		)
		(duplicate_pad_numbers_are_jumpers no)
		(fp_rect
			(start 0.4318 0.9525)
			(end -0.4318 -0.9525)
			(stroke
				(width 0)
				(type default)
			)
			(fill no)
			(layer "B.CrtYd")
		)
		(fp_rect
			(start 0.4318 0.9525)
			(end -0.4318 -0.9525)
			(stroke
				(width 0)
				(type default)
			)
			(fill no)
			(layer "B.Fab")
		)
		(pad "1" smd custom
			(at 0 -0.4445)
			(size 0.1524 0.1524)
			(layers "B.Cu" "B.Mask" "B.Paste")
			(net "P1V8")
			(options
				(clearance outline)
				(anchor circle)
			)
			(primitives
				(gr_poly
					(pts
						(arc
							(start 0.3048 0.2032)
							(mid 0.275042 0.275042)
							(end 0.2032 0.3048)
						)
						(arc
							(start -0.2032 0.3048)
							(mid -0.275042 0.275042)
							(end -0.3048 0.2032)
						)
						(arc
							(start -0.3048 -0.2032)
							(mid -0.275042 -0.275042)
							(end -0.2032 -0.3048)
						)
						(arc
							(start 0.2032 -0.3048)
							(mid 0.275042 -0.275042)
							(end 0.3048 -0.2032)
						)
					)
					(width 0)
					(fill yes)
				)
			)
		)
		(pad "2" smd custom
			(at 0 0.4445)
			(size 0.1524 0.1524)
			(layers "B.Cu" "B.Mask" "B.Paste")
			(net "GND")
			(options
				(clearance outline)
				(anchor circle)
			)
			(primitives
				(gr_poly
					(pts
						(arc
							(start 0.3048 0.2032)
							(mid 0.275042 0.275042)
							(end 0.2032 0.3048)
						)
						(arc
							(start -0.2032 0.3048)
							(mid -0.275042 0.275042)
							(end -0.3048 0.2032)
						)
						(arc
							(start -0.3048 -0.2032)
							(mid -0.275042 -0.275042)
							(end -0.2032 -0.3048)
						)
						(arc
							(start 0.2032 -0.3048)
							(mid 0.275042 -0.275042)
							(end 0.3048 -0.2032)
						)
					)
					(width 0)
					(fill yes)
				)
			)
		)
	)
	(footprint ""
		(layer "B.Cu")
		(at 38.43401 -121.142252 90)
		(property "Reference" "R282"
			(at 0 0 90)
			(layer "B.SilkS")
			(hide yes)
			(effects
				(font
					(size 1.27 1.27)
				)
				(justify mirror)
			)
		)
		(property "Value" "4K7R2F-GP"
			(at -0.064008 -3.993896 90)
			(unlocked yes)
			(layer "B.Fab")
			(hide yes)
			(effects
				(font
					(size 1.016 1.016)
					(thickness 0.1524)
				)
				(justify mirror)
			)
		)
		(property "Device Type" "R402H16"
			(at -0.064008 -5.517896 90)
			(unlocked yes)
			(layer "B.Fab")
			(hide yes)
			(effects
				(font
					(size 1.016 1.016)
					(thickness 0.1524)
				)
				(justify mirror)
			)
		)
		(duplicate_pad_numbers_are_jumpers no)
		(fp_line
			(start 0.508 -0.9398)
			(end 0.508 0.9398)
			(stroke
				(width 0.1524)
				(type default)
			)
			(layer "B.SilkS")
		)
		(fp_line
			(start -0.508 -0.9398)
			(end 0.508 -0.9398)
			(stroke
				(width 0.1524)
				(type default)
			)
			(layer "B.SilkS")
		)
		(fp_rect
			(start 0.508 0.9398)
			(end -0.508 -0.9398)
			(stroke
				(width 0)
				(type default)
			)
			(fill no)
			(layer "B.CrtYd")
		)
		(fp_rect
			(start 0.508 0.9398)
			(end -0.508 -0.9398)
			(stroke
				(width 0)
				(type default)
			)
			(fill no)
			(layer "B.Fab")
		)
		(pad "1" smd custom
			(at 0 -0.4445 270)
			(size 0.1397 0.1397)
			(layers "B.Cu" "B.Mask" "B.Paste")
			(net "P3V3_STBY")
			(options
				(clearance outline)
				(anchor circle)
			)
			(primitives
				(gr_poly
					(pts
						(arc
							(start -0.1778 0.2794)
							(mid -0.249642 0.249642)
							(end -0.2794 0.1778)
						)
						(arc
							(start -0.2794 -0.1778)
							(mid -0.249642 -0.249642)
							(end -0.1778 -0.2794)
						)
						(arc
							(start 0.1778 -0.2794)
							(mid 0.249642 -0.249642)
							(end 0.2794 -0.1778)
						)
						(arc
							(start 0.2794 0.1778)
							(mid 0.249642 0.249642)
							(end 0.1778 0.2794)
						)
					)
					(width 0)
					(fill yes)
				)
			)
		)
		(pad "2" smd custom
			(at 0 0.4445 270)
			(size 0.1397 0.1397)
			(layers "B.Cu" "B.Mask" "B.Paste")
			(net "TEMP_3_A0")
			(options
				(clearance outline)
				(anchor circle)
			)
			(primitives
				(gr_poly
					(pts
						(arc
							(start -0.1778 0.2794)
							(mid -0.249642 0.249642)
							(end -0.2794 0.1778)
						)
						(arc
							(start -0.2794 -0.1778)
							(mid -0.249642 -0.249642)
							(end -0.1778 -0.2794)
						)
						(arc
							(start 0.1778 -0.2794)
							(mid 0.249642 -0.249642)
							(end 0.2794 -0.1778)
						)
						(arc
							(start 0.2794 0.1778)
							(mid 0.249642 0.249642)
							(end 0.1778 0.2794)
						)
					)
					(width 0)
					(fill yes)
				)
			)
		)
	)
	(footprint ""
		(layer "B.Cu")
		(at 42.3418 -128.2192)
		(property "Reference" "R325"
			(at 0 0 0)
			(layer "B.SilkS")
			(hide yes)
			(effects
				(font
					(size 1.27 1.27)
				)
				(justify mirror)
			)
		)
		(property "Value" "0R2J-2-GP"
			(at -0.064008 -3.993896 0)
			(unlocked yes)
			(layer "B.Fab")
			(hide yes)
			(effects
				(font
					(size 1.016 1.016)
					(thickness 0.1524)
				)
				(justify mirror)
			)
		)
		(property "Device Type" "R402H16"
			(at -0.064008 -5.517896 0)
			(unlocked yes)
			(layer "B.Fab")
			(hide yes)
			(effects
				(font
					(size 1.016 1.016)
					(thickness 0.1524)
				)
				(justify mirror)
			)
		)
		(duplicate_pad_numbers_are_jumpers no)
		(fp_line
			(start -0.508 -0.9398)
			(end 0.508 -0.9398)
			(stroke
				(width 0.1524)
				(type default)
			)
			(layer "B.SilkS")
		)
		(fp_line
			(start 0.508 -0.9398)
			(end 0.508 0.9398)
			(stroke
				(width 0.1524)
				(type default)
			)
			(layer "B.SilkS")
		)
		(fp_rect
			(start 0.508 0.9398)
			(end -0.508 -0.9398)
			(stroke
				(width 0)
				(type default)
			)
			(fill no)
			(layer "B.CrtYd")
		)
		(fp_rect
			(start 0.508 0.9398)
			(end -0.508 -0.9398)
			(stroke
				(width 0)
				(type default)
			)
			(fill no)
			(layer "B.Fab")
		)
		(pad "1" smd custom
			(at 0 -0.4445 180)
			(size 0.1397 0.1397)
			(layers "B.Cu" "B.Mask" "B.Paste")
			(net "BMC0_SRST_N")
			(options
				(clearance outline)
				(anchor circle)
			)
			(primitives
				(gr_poly
					(pts
						(arc
							(start -0.1778 0.2794)
							(mid -0.249642 0.249642)
							(end -0.2794 0.1778)
						)
						(arc
							(start -0.2794 -0.1778)
							(mid -0.249642 -0.249642)
							(end -0.1778 -0.2794)
						)
						(arc
							(start 0.1778 -0.2794)
							(mid 0.249642 -0.249642)
							(end 0.2794 -0.1778)
						)
						(arc
							(start 0.2794 0.1778)
							(mid 0.249642 0.249642)
							(end 0.1778 0.2794)
						)
					)
					(width 0)
					(fill yes)
				)
			)
		)
		(pad "2" smd custom
			(at 0 0.4445 180)
			(size 0.1397 0.1397)
			(layers "B.Cu" "B.Mask" "B.Paste")
			(net "FM_BMC_RESET_N")
			(options
				(clearance outline)
				(anchor circle)
			)
			(primitives
				(gr_poly
					(pts
						(arc
							(start -0.1778 0.2794)
							(mid -0.249642 0.249642)
							(end -0.2794 0.1778)
						)
						(arc
							(start -0.2794 -0.1778)
							(mid -0.249642 -0.249642)
							(end -0.1778 -0.2794)
						)
						(arc
							(start 0.1778 -0.2794)
							(mid 0.249642 -0.249642)
							(end 0.2794 -0.1778)
						)
						(arc
							(start 0.2794 0.1778)
							(mid 0.249642 0.249642)
							(end 0.1778 0.2794)
						)
					)
					(width 0)
					(fill yes)
				)
			)
		)
	)
	(footprint ""
		(layer "B.Cu")
		(at 188.2394 -78.0796)
		(property "Reference" "TP87"
			(at 0 0 0)
			(layer "B.SilkS")
			(hide yes)
			(effects
				(font
					(size 1.27 1.27)
				)
				(justify mirror)
			)
		)
		(property "Value" "TPAD28-2-GP"
			(at 0.0127 -1.6637 0)
			(unlocked yes)
			(layer "B.Fab")
			(hide yes)
			(effects
				(font
					(size 1.016 1.016)
					(thickness 0.1524)
				)
				(justify mirror)
			)
		)
		(property "Device Type" "TPAD28"
			(at 0.0127 -3.1877 0)
			(unlocked yes)
			(layer "B.Fab")
			(hide yes)
			(effects
				(font
					(size 1.016 1.016)
					(thickness 0.1524)
				)
				(justify mirror)
			)
		)
		(duplicate_pad_numbers_are_jumpers no)
		(fp_poly
			(pts
				(arc
					(start 0.3556 0)
					(mid -0.3556 0)
					(end 0.3556 0)
				)
			)
			(stroke
				(width 0)
				(type default)
			)
			(fill no)
			(layer "B.CrtYd")
		)
		(fp_poly
			(pts
				(arc
					(start 0.6096 0)
					(mid -0.6096 0)
					(end 0.6096 0)
				)
			)
			(stroke
				(width 0)
				(type default)
			)
			(fill no)
			(layer "B.Fab")
		)
		(pad "1" smd circle
			(at 0 0 180)
			(size 0.7112 0.7112)
			(layers "B.Cu" "B.Mask" "B.Paste")
			(net "IOC_GPIO_2")
		)
	)
)
